# T6G (Grand Teton) — schematic netlist excerpt (pin names and nets, part order shuffled) for the footprints in the layout excerpt that follows; sources: Cadence DE-HDL packaged netlist, KiCad conversion of 04192023_DAF0TMB3IC0_F0TG_MB_C_brd_V02_OCP.brd

R761  Q_RES  15.4K 1% CHIP  pkg 0402LF  page 87 : A = PD_CHB_CPU0_DIMM_SAA ; B = GND
R2807  Q_RES  4.7K 5% EMPTY  pkg 0402LF  page 240 : A = P3V3_AUX ; B = SMB_FAN_3V3AUX_BUF_SDA
PC190_3  Q_CAP  22UF 4V 20% X6S  pkg C0805  page 206 : A = PVDDIO_P0 ; B = GND

(kicad_pcb
	(version 20260206)
	(generator "pcbnew")
	(generator_version "10.0")
	(general
		(thickness 1.6)
		(legacy_teardrops no)
	)
	(paper "A4")
	(title_block
		(title "04192023_DAF0TMB3IC0_F0TG_MB_C_brd_V02_OCP.brd")
		(comment 1 "Grand Teton / footprints 6206-6208 of 8354")
	)
	(layers
		(0 "F.Cu" signal "TOP")
		(4 "In1.Cu" signal "GND")
		(6 "In2.Cu" signal "IN1")
		(8 "In3.Cu" signal "GND1")
		(10 "In4.Cu" signal "IN2")
		(12 "In5.Cu" signal "GND2")
		(14 "In6.Cu" signal "IN3")
		(16 "In7.Cu" signal "GND3")
		(18 "In8.Cu" signal "VCC")
		(20 "In9.Cu" signal "VCC1")
		(22 "In10.Cu" signal "GND4")
		(24 "In11.Cu" signal "IN4")
		(26 "In12.Cu" signal "GND5")
		(28 "In13.Cu" signal "IN5")
		(30 "In14.Cu" signal "GND6")
		(32 "In15.Cu" signal "IN6")
		(34 "In16.Cu" signal "GND7")
		(2 "B.Cu" signal "BOTTOM")
		(9 "F.Adhes" user "F.Adhesive")
		(11 "B.Adhes" user "B.Adhesive")
		(13 "F.Paste" user "Package Geometry/Pastemask Top")
		(15 "B.Paste" user "Package Geometry/Pastemask Bottom")
		(5 "F.SilkS" user "Ref Des/Silkscreen Top")
		(7 "B.SilkS" user "Ref Des/Silkscreen Bottom")
		(1 "F.Mask" user "Board Geometry/Soldermask Top")
		(3 "B.Mask" user "Board Geometry/Soldermask Bottom")
		(17 "Dwgs.User" user "User.Drawings")
		(19 "Cmts.User" user "User.Comments")
		(21 "Eco1.User" user "User.Eco1")
		(23 "Eco2.User" user "User.Eco2")
		(25 "Edge.Cuts" user "Board Geometry/Outline")
		(27 "Margin" user)
		(31 "F.CrtYd" user "Package Geometry/Place Bound Top")
		(29 "B.CrtYd" user "Package Geometry/Place Bound Bottom")
		(35 "F.Fab" user "Ref Des/Assembly Top")
		(33 "B.Fab" user "Ref Des/Assembly Bottom")
	)
	(footprint ""
		(layer "B.Cu")
		(at 296.479722 -194.88531 180)
		(property "Reference" "R761"
			(at 0 0 0)
			(layer "B.SilkS")
			(hide yes)
			(effects
				(font
					(size 1.27 1.27)
				)
				(justify mirror)
			)
		)
		(property "Value" ""
			(at 0 0 0)
			(layer "B.Fab")
			(effects
				(font
					(size 1.27 1.27)
				)
				(justify mirror)
			)
		)
		(duplicate_pad_numbers_are_jumpers no)
		(fp_line
			(start 0.7874 0.4064)
			(end 0.7874 -0.4064)
			(stroke
				(width 0.1524)
				(type default)
			)
			(layer "B.SilkS")
		)
		(fp_line
			(start 0.7874 -0.4064)
			(end -0.7874 -0.4064)
			(stroke
				(width 0.1524)
				(type default)
			)
			(layer "B.SilkS")
		)
		(fp_line
			(start -0.7874 0.4064)
			(end 0.7874 0.4064)
			(stroke
				(width 0.1524)
				(type default)
			)
			(layer "B.SilkS")
		)
		(fp_line
			(start -0.7874 -0.4064)
			(end -0.7874 0.4064)
			(stroke
				(width 0.1524)
				(type default)
			)
			(layer "B.SilkS")
		)
		(fp_line
			(start 0.67945 0.3048)
			(end 0.67945 -0.305054)
			(stroke
				(width 0.1)
				(type default)
			)
			(layer "B.Fab")
		)
		(fp_line
			(start 0.67945 -0.305054)
			(end 0.12065 -0.305054)
			(stroke
				(width 0.1)
				(type default)
			)
			(layer "B.Fab")
		)
		(fp_line
			(start 0.12065 0.3048)
			(end 0.67945 0.3048)
			(stroke
				(width 0.1)
				(type default)
			)
			(layer "B.Fab")
		)
		(fp_line
			(start 0.12065 0.2794)
			(end 0.12065 0.3048)
			(stroke
				(width 0.1)
				(type default)
			)
			(layer "B.Fab")
		)
		(fp_line
			(start 0.12065 -0.2794)
			(end -0.12065 -0.2794)
			(stroke
				(width 0.1)
				(type default)
			)
			(layer "B.Fab")
		)
		(fp_line
			(start 0.12065 -0.305054)
			(end 0.12065 -0.2794)
			(stroke
				(width 0.1)
				(type default)
			)
			(layer "B.Fab")
		)
		(fp_line
			(start -0.120396 0.3048)
			(end -0.120396 0.2794)
			(stroke
				(width 0.1)
				(type default)
			)
			(layer "B.Fab")
		)
		(fp_line
			(start -0.120396 0.2794)
			(end 0.12065 0.2794)
			(stroke
				(width 0.1)
				(type default)
			)
			(layer "B.Fab")
		)
		(fp_line
			(start -0.12065 -0.2794)
			(end -0.12065 -0.3048)
			(stroke
				(width 0.1)
				(type default)
			)
			(layer "B.Fab")
		)
		(fp_line
			(start -0.12065 -0.3048)
			(end -0.67945 -0.3048)
			(stroke
				(width 0.1)
				(type default)
			)
			(layer "B.Fab")
		)
		(fp_line
			(start -0.67945 0.3048)
			(end -0.120396 0.3048)
			(stroke
				(width 0.1)
				(type default)
			)
			(layer "B.Fab")
		)
		(fp_line
			(start -0.67945 -0.3048)
			(end -0.67945 0.3048)
			(stroke
				(width 0.1)
				(type default)
			)
			(layer "B.Fab")
		)
		(pad "1" smd circle
			(at 0.40005 0)
			(size 0 0)
			(layers "B.Cu" "B.Mask" "B.Paste")
			(net "PD_CHB_CPU0_DIMM_SAA")
		)
		(pad "2" smd circle
			(at -0.40005 0)
			(size 0 0)
			(layers "B.Cu" "B.Mask" "B.Paste")
			(net "GND")
		)
	)
	(footprint ""
		(layer "B.Cu")
		(at 287.933384 -337.984846 -90)
		(property "Reference" "PC190_3"
			(at 0 0 90)
			(layer "B.SilkS")
			(hide yes)
			(effects
				(font
					(size 1.27 1.27)
				)
				(justify mirror)
			)
		)
		(property "Value" ""
			(at 0 0 90)
			(layer "B.Fab")
			(effects
				(font
					(size 1.27 1.27)
				)
				(justify mirror)
			)
		)
		(duplicate_pad_numbers_are_jumpers no)
		(fp_line
			(start -1.524 0.762)
			(end 1.524 0.762)
			(stroke
				(width 0.1524)
				(type default)
			)
			(layer "B.SilkS")
		)
		(fp_line
			(start 1.524 0.762)
			(end 1.524 -0.762)
			(stroke
				(width 0.1524)
				(type default)
			)
			(layer "B.SilkS")
		)
		(fp_line
			(start -1.524 -0.762)
			(end -1.524 0.762)
			(stroke
				(width 0.1524)
				(type default)
			)
			(layer "B.SilkS")
		)
		(fp_line
			(start 1.524 -0.762)
			(end -1.524 -0.762)
			(stroke
				(width 0.1524)
				(type default)
			)
			(layer "B.SilkS")
		)
		(fp_line
			(start -1.1049 0.724916)
			(end -1.1049 -0.724916)
			(stroke
				(width 0.1)
				(type default)
			)
			(layer "B.Fab")
		)
		(fp_line
			(start 1.1049 0.724916)
			(end -1.1049 0.724916)
			(stroke
				(width 0.1)
				(type default)
			)
			(layer "B.Fab")
		)
		(fp_line
			(start -1.1049 -0.724916)
			(end 1.1049 -0.724916)
			(stroke
				(width 0.1)
				(type default)
			)
			(layer "B.Fab")
		)
		(fp_line
			(start 1.1049 -0.724916)
			(end 1.1049 0.724916)
			(stroke
				(width 0.1)
				(type default)
			)
			(layer "B.Fab")
		)
		(pad "1" smd rect
			(at 0.889 0 270)
			(size 1.016 1.27)
			(layers "B.Cu" "B.Mask" "B.Paste")
			(net "PVDDIO_P0")
		)
		(pad "2" smd rect
			(at -0.889 0 270)
			(size 1.016 1.27)
			(layers "B.Cu" "B.Mask" "B.Paste")
			(net "GND")
		)
	)
	(footprint ""
		(layer "B.Cu")
		(at 172.312838 -419.206426 180)
		(property "Reference" "R2807"
			(at 0 0 0)
			(layer "B.SilkS")
			(hide yes)
			(effects
				(font
					(size 1.27 1.27)
				)
				(justify mirror)
			)
		)
		(property "Value" ""
			(at 0 0 0)
			(layer "B.Fab")
			(effects
				(font
					(size 1.27 1.27)
				)
				(justify mirror)
			)
		)
		(duplicate_pad_numbers_are_jumpers no)
		(fp_line
			(start 0.7874 0.4064)
			(end 0.7874 -0.4064)
			(stroke
				(width 0.1524)
				(type default)
			)
			(layer "B.SilkS")
		)
		(fp_line
			(start 0.7874 -0.4064)
			(end -0.7874 -0.4064)
			(stroke
				(width 0.1524)
				(type default)
			)
			(layer "B.SilkS")
		)
		(fp_line
			(start -0.7874 0.4064)
			(end 0.7874 0.4064)
			(stroke
				(width 0.1524)
				(type default)
			)
			(layer "B.SilkS")
		)
		(fp_line
			(start -0.7874 -0.4064)
			(end -0.7874 0.4064)
			(stroke
				(width 0.1524)
				(type default)
			)
			(layer "B.SilkS")
		)
		(fp_line
			(start 0.67945 0.3048)
			(end 0.67945 -0.305054)
			(stroke
				(width 0.1)
				(type default)
			)
			(layer "B.Fab")
		)
		(fp_line
			(start 0.67945 -0.305054)
			(end 0.12065 -0.305054)
			(stroke
				(width 0.1)
				(type default)
			)
			(layer "B.Fab")
		)
		(fp_line
			(start 0.12065 0.3048)
			(end 0.67945 0.3048)
			(stroke
				(width 0.1)
				(type default)
			)
			(layer "B.Fab")
		)
		(fp_line
			(start 0.12065 0.2794)
			(end 0.12065 0.3048)
			(stroke
				(width 0.1)
				(type default)
			)
			(layer "B.Fab")
		)
		(fp_line
			(start 0.12065 -0.2794)
			(end -0.12065 -0.2794)
			(stroke
				(width 0.1)
				(type default)
			)
			(layer "B.Fab")
		)
		(fp_line
			(start 0.12065 -0.305054)
			(end 0.12065 -0.2794)
			(stroke
				(width 0.1)
				(type default)
			)
			(layer "B.Fab")
		)
		(fp_line
			(start -0.120396 0.3048)
			(end -0.120396 0.2794)
			(stroke
				(width 0.1)
				(type default)
			)
			(layer "B.Fab")
		)
		(fp_line
			(start -0.120396 0.2794)
			(end 0.12065 0.2794)
			(stroke
				(width 0.1)
				(type default)
			)
			(layer "B.Fab")
		)
		(fp_line
			(start -0.12065 -0.2794)
			(end -0.12065 -0.3048)
			(stroke
				(width 0.1)
				(type default)
			)
			(layer "B.Fab")
		)
		(fp_line
			(start -0.12065 -0.3048)
			(end -0.67945 -0.3048)
			(stroke
				(width 0.1)
				(type default)
			)
			(layer "B.Fab")
		)
		(fp_line
			(start -0.67945 0.3048)
			(end -0.120396 0.3048)
			(stroke
				(width 0.1)
				(type default)
			)
			(layer "B.Fab")
		)
		(fp_line
			(start -0.67945 -0.3048)
			(end -0.67945 0.3048)
			(stroke
				(width 0.1)
				(type default)
			)
			(layer "B.Fab")
		)
		(pad "1" smd circle
			(at 0.40005 0)
			(size 0 0)
			(layers "B.Cu" "B.Mask" "B.Paste")
			(net "P3V3_AUX")
		)
		(pad "2" smd circle
			(at -0.40005 0)
			(size 0 0)
			(layers "B.Cu" "B.Mask" "B.Paste")
			(net "SMB_FAN_3V3AUX_BUF_SDA")
		)
	)
)
